FILE_TYPE = CONNECTIVITY;
{Allegro Design Entry HDL 17.2-2016 S081 (4005846) 1/11/2022}
"PAGE_NUMBER" = 33;
0"NC";
END.
